FILE_TYPE = MACRO_DRAWING;
SET COLOR_WIRE YELLOW;
SET COLOR_PROP MONO;
SET COLOR_DOT WHITE;
SET COLOR_ARC YELLOW;
SET COLOR_BODY GREEN;
SET COLOR_NOTE MONO;
SET PROP_DISPLAY VALUE;
SET PAGE_NUMBER P73;
FORCEADD VCC_CORE..1
(-1800 4100);
FORCEPROP 3 LASTPIN (-1800 4050) SIG_NAME PVCCMCP_CPU1\g
J 0
(-1790 4060);
DISPLAY 0.659574 (-1790 4060);
PAINT MONO (-1790 4060);
DISPLAY INVISIBLE (-1790 4060);
FORCEPROP 1 LAST HDL_POWER PVCCMCP_CPU1
J 1
(-1800 4150);
DISPLAY 0.617021 (-1800 4150);
PAINT GREEN (-1800 4150);
FORCEPROP 2 LAST CDS_LIB mstr_symbols
J 0
(-1800 4100);
PAINT ORANGE (-1800 4100);
DISPLAY INVISIBLE (-1800 4100);
FORCEPROP 1 LAST PATH I104
J 0
(-1750 4125);
DISPLAY 0.872340 (-1750 4125);
PAINT AQUA (-1750 4125);
DISPLAY INVISIBLE (-1750 4125);
FORCEADD VCC_CORE..1
(-6600 1975);
FORCEPROP 3 LASTPIN (-6600 1925) SIG_NAME PVCCMCP_CPU1\g
J 0
(-6590 1935);
DISPLAY 0.659574 (-6590 1935);
PAINT MONO (-6590 1935);
DISPLAY INVISIBLE (-6590 1935);
FORCEPROP 1 LAST HDL_POWER PVCCMCP_CPU1
J 1
(-6600 2025);
DISPLAY 0.617021 (-6600 2025);
PAINT GREEN (-6600 2025);
FORCEPROP 2 LAST CDS_LIB mstr_symbols
J 0
(-6600 1975);
PAINT ORANGE (-6600 1975);
DISPLAY INVISIBLE (-6600 1975);
FORCEPROP 1 LAST PATH I105
J 0
(-6550 2000);
DISPLAY 0.872340 (-6550 2000);
PAINT AQUA (-6550 2000);
DISPLAY INVISIBLE (-6550 2000);
FORCEADD SKX_EXT_B..22
(-4000 2550);
FORCEPROP 1 LAST LOCATION U2D1
J 0
(-5000 4200);
DISPLAY 0.617021 (-5000 4200);
PAINT AQUA (-5000 4200);
FORCEPROP 1 LAST PART_NUMBER TBD
J 0
(-5000 750);
DISPLAY 0.617021 (-5000 750);
PAINT BLUE (-5000 750);
FORCEPROP 1 LAST MATERIAL IC
J 0
(-5000 4150);
DISPLAY 0.617021 (-5000 4150);
PAINT SKYBLUE (-5000 4150);
FORCEPROP 2 LASTPIN (-5050 2450) $PN CG76
J 2
(-5060 2460);
DISPLAY 0.617021 (-5060 2460);
PAINT ORANGE (-5060 2460);
FORCEPROP 2 LASTPIN (-5050 2000) $PN BF5
J 2
(-5060 2010);
DISPLAY 0.617021 (-5060 2010);
PAINT ORANGE (-5060 2010);
FORCEPROP 2 LASTPIN (-5050 2500) $PN CE76
J 2
(-5060 2510);
DISPLAY 0.617021 (-5060 2510);
PAINT ORANGE (-5060 2510);
FORCEPROP 2 LASTPIN (-5050 2050) $PN BH5
J 2
(-5060 2060);
DISPLAY 0.617021 (-5060 2060);
PAINT ORANGE (-5060 2060);
FORCEPROP 2 LASTPIN (-5050 3950) $PN CN6
J 2
(-5060 3960);
DISPLAY 0.617021 (-5060 3960);
PAINT ORANGE (-5060 3960);
FORCEPROP 2 LASTPIN (-5050 3900) $PN CU12
J 2
(-5060 3910);
DISPLAY 0.617021 (-5060 3910);
PAINT ORANGE (-5060 3910);
FORCEPROP 2 LASTPIN (-5050 3800) $PN CV21
J 2
(-5060 3810);
DISPLAY 0.617021 (-5060 3810);
PAINT ORANGE (-5060 3810);
FORCEPROP 2 LASTPIN (-5050 3750) $PN CU18
J 2
(-5060 3760);
DISPLAY 0.617021 (-5060 3760);
PAINT ORANGE (-5060 3760);
FORCEPROP 2 LASTPIN (-5050 3700) $PN CY17
J 2
(-5060 3710);
DISPLAY 0.617021 (-5060 3710);
PAINT ORANGE (-5060 3710);
FORCEPROP 2 LASTPIN (-5050 3650) $PN DC18
J 2
(-5060 3660);
DISPLAY 0.617021 (-5060 3660);
PAINT ORANGE (-5060 3660);
FORCEPROP 2 LASTPIN (-5050 3600) $PN DE14
J 2
(-5060 3610);
DISPLAY 0.617021 (-5060 3610);
PAINT ORANGE (-5060 3610);
FORCEPROP 2 LASTPIN (-5050 3550) $PN CP13
J 2
(-5060 3560);
DISPLAY 0.617021 (-5060 3560);
PAINT ORANGE (-5060 3560);
FORCEPROP 2 LASTPIN (-5050 3500) $PN CL20
J 2
(-5060 3510);
DISPLAY 0.617021 (-5060 3510);
PAINT ORANGE (-5060 3510);
FORCEPROP 2 LASTPIN (-5050 3450) $PN CG14
J 2
(-5060 3460);
DISPLAY 0.617021 (-5060 3460);
PAINT ORANGE (-5060 3460);
FORCEPROP 2 LASTPIN (-5050 3350) $PN CF5
J 2
(-5060 3360);
DISPLAY 0.617021 (-5060 3360);
PAINT ORANGE (-5060 3360);
FORCEPROP 2 LASTPIN (-5050 3300) $PN DK21
J 2
(-5060 3310);
DISPLAY 0.617021 (-5060 3310);
PAINT ORANGE (-5060 3310);
FORCEPROP 2 LASTPIN (-5050 3250) $PN BE24
J 2
(-5060 3260);
DISPLAY 0.617021 (-5060 3260);
PAINT ORANGE (-5060 3260);
FORCEPROP 2 LASTPIN (-5050 3200) $PN AT7
J 2
(-5060 3210);
DISPLAY 0.617021 (-5060 3210);
PAINT ORANGE (-5060 3210);
FORCEPROP 2 LASTPIN (-5050 3150) $PN AT5
J 2
(-5060 3160);
DISPLAY 0.617021 (-5060 3160);
PAINT ORANGE (-5060 3160);
FORCEPROP 2 LASTPIN (-5050 3100) $PN AM5
J 2
(-5060 3110);
DISPLAY 0.617021 (-5060 3110);
PAINT ORANGE (-5060 3110);
FORCEPROP 2 LASTPIN (-5050 3050) $PN DV11
J 2
(-5060 3060);
DISPLAY 0.617021 (-5060 3060);
PAINT ORANGE (-5060 3060);
FORCEPROP 2 LASTPIN (-5050 3000) $PN AF5
J 2
(-5060 3010);
DISPLAY 0.617021 (-5060 3010);
PAINT ORANGE (-5060 3010);
FORCEPROP 2 LASTPIN (-5050 2950) $PN AE10
J 2
(-5060 2960);
DISPLAY 0.617021 (-5060 2960);
PAINT ORANGE (-5060 2960);
FORCEPROP 2 LASTPIN (-5050 2900) $PN EE10
J 2
(-5060 2910);
DISPLAY 0.617021 (-5060 2910);
PAINT ORANGE (-5060 2910);
FORCEPROP 2 LASTPIN (-5050 2800) $PN CL26
J 2
(-5060 2810);
DISPLAY 0.617021 (-5060 2810);
PAINT ORANGE (-5060 2810);
FORCEPROP 2 LASTPIN (-5050 2750) $PN CM23
J 2
(-5060 2760);
DISPLAY 0.617021 (-5060 2760);
PAINT ORANGE (-5060 2760);
FORCEPROP 2 LASTPIN (-5050 2700) $PN CM25
J 2
(-5060 2710);
DISPLAY 0.617021 (-5060 2710);
PAINT ORANGE (-5060 2710);
FORCEPROP 2 LASTPIN (-5050 2650) $PN CN22
J 2
(-5060 2660);
DISPLAY 0.617021 (-5060 2660);
PAINT ORANGE (-5060 2660);
FORCEPROP 2 LASTPIN (-5050 2600) $PN CN24
J 2
(-5060 2610);
DISPLAY 0.617021 (-5060 2610);
PAINT ORANGE (-5060 2610);
FORCEPROP 2 LASTPIN (-5050 1900) $PN CN28
J 2
(-5060 1910);
DISPLAY 0.617021 (-5060 1910);
PAINT ORANGE (-5060 1910);
FORCEPROP 2 LASTPIN (-5050 1850) $PN CP23
J 2
(-5060 1860);
DISPLAY 0.617021 (-5060 1860);
PAINT ORANGE (-5060 1860);
FORCEPROP 2 LASTPIN (-5050 1800) $PN CP31
J 2
(-5060 1810);
DISPLAY 0.617021 (-5060 1810);
PAINT ORANGE (-5060 1810);
FORCEPROP 2 LASTPIN (-5050 1750) $PN CR60
J 2
(-5060 1760);
DISPLAY 0.617021 (-5060 1760);
PAINT ORANGE (-5060 1760);
FORCEPROP 2 LASTPIN (-5050 1700) $PN CT23
J 2
(-5060 1710);
DISPLAY 0.617021 (-5060 1710);
PAINT ORANGE (-5060 1710);
FORCEPROP 2 LASTPIN (-5050 1650) $PN CT5
J 2
(-5060 1660);
DISPLAY 0.617021 (-5060 1660);
PAINT ORANGE (-5060 1660);
FORCEPROP 2 LASTPIN (-5050 1600) $PN CT69
J 2
(-5060 1610);
DISPLAY 0.617021 (-5060 1610);
PAINT ORANGE (-5060 1610);
FORCEPROP 2 LASTPIN (-5050 1550) $PN CU24
J 2
(-5060 1560);
DISPLAY 0.617021 (-5060 1560);
PAINT ORANGE (-5060 1560);
FORCEPROP 2 LASTPIN (-5050 1500) $PN CU6
J 2
(-5060 1510);
DISPLAY 0.617021 (-5060 1510);
PAINT ORANGE (-5060 1510);
FORCEPROP 2 LASTPIN (-5050 1450) $PN CU60
J 2
(-5060 1460);
DISPLAY 0.617021 (-5060 1460);
PAINT ORANGE (-5060 1460);
FORCEPROP 2 LASTPIN (-5050 1400) $PN CV23
J 2
(-5060 1410);
DISPLAY 0.617021 (-5060 1410);
PAINT ORANGE (-5060 1410);
FORCEPROP 2 LASTPIN (-5050 1350) $PN CV69
J 2
(-5060 1360);
DISPLAY 0.617021 (-5060 1360);
PAINT ORANGE (-5060 1360);
FORCEPROP 2 LASTPIN (-5050 1300) $PN CW22
J 2
(-5060 1310);
DISPLAY 0.617021 (-5060 1310);
PAINT ORANGE (-5060 1310);
FORCEPROP 2 LASTPIN (-5050 1250) $PN CW24
J 2
(-5060 1260);
DISPLAY 0.617021 (-5060 1260);
PAINT ORANGE (-5060 1260);
FORCEPROP 2 LASTPIN (-5050 1200) $PN CW60
J 2
(-5060 1210);
DISPLAY 0.617021 (-5060 1210);
PAINT ORANGE (-5060 1210);
FORCEPROP 2 LASTPIN (-2950 3950) $PN CW62
J 0
(-2940 3960);
DISPLAY 0.617021 (-2940 3960);
PAINT ORANGE (-2940 3960);
FORCEPROP 2 LASTPIN (-2950 3900) $PN CY23
J 0
(-2940 3910);
DISPLAY 0.617021 (-2940 3910);
PAINT ORANGE (-2940 3910);
FORCEPROP 2 LASTPIN (-2950 3850) $PN CY25
J 0
(-2940 3860);
DISPLAY 0.617021 (-2940 3860);
PAINT ORANGE (-2940 3860);
FORCEPROP 2 LASTPIN (-2950 3800) $PN CY39
J 0
(-2940 3810);
DISPLAY 0.617021 (-2940 3810);
PAINT ORANGE (-2940 3810);
FORCEPROP 2 LASTPIN (-2950 3750) $PN CY53
J 0
(-2940 3760);
DISPLAY 0.617021 (-2940 3760);
PAINT ORANGE (-2940 3760);
FORCEPROP 2 LASTPIN (-2950 3700) $PN CY57
J 0
(-2940 3710);
DISPLAY 0.617021 (-2940 3710);
PAINT ORANGE (-2940 3710);
FORCEPROP 2 LASTPIN (-2950 3650) $PN CY63
J 0
(-2940 3660);
DISPLAY 0.617021 (-2940 3660);
PAINT ORANGE (-2940 3660);
FORCEPROP 2 LASTPIN (-2950 3600) $PN CY73
J 0
(-2940 3610);
DISPLAY 0.617021 (-2940 3610);
PAINT ORANGE (-2940 3610);
FORCEPROP 2 LASTPIN (-2950 3550) $PN DA24
J 0
(-2940 3560);
DISPLAY 0.617021 (-2940 3560);
PAINT ORANGE (-2940 3560);
FORCEPROP 2 LASTPIN (-2950 3500) $PN DA40
J 0
(-2940 3510);
DISPLAY 0.617021 (-2940 3510);
PAINT ORANGE (-2940 3510);
FORCEPROP 2 LASTPIN (-2950 3450) $PN DA52
J 0
(-2940 3460);
DISPLAY 0.617021 (-2940 3460);
PAINT ORANGE (-2940 3460);
FORCEPROP 2 LASTPIN (-2950 3400) $PN DA54
J 0
(-2940 3410);
DISPLAY 0.617021 (-2940 3410);
PAINT ORANGE (-2940 3410);
FORCEPROP 2 LASTPIN (-2950 3350) $PN DA56
J 0
(-2940 3360);
DISPLAY 0.617021 (-2940 3360);
PAINT ORANGE (-2940 3360);
FORCEPROP 2 LASTPIN (-2950 3300) $PN DC46
J 0
(-2940 3310);
DISPLAY 0.617021 (-2940 3310);
PAINT ORANGE (-2940 3310);
FORCEPROP 2 LASTPIN (-2950 3250) $PN DC52
J 0
(-2940 3260);
DISPLAY 0.617021 (-2940 3260);
PAINT ORANGE (-2940 3260);
FORCEPROP 2 LASTPIN (-2950 3200) $PN DD51
J 0
(-2940 3210);
DISPLAY 0.617021 (-2940 3210);
PAINT ORANGE (-2940 3210);
FORCEPROP 2 LASTPIN (-2950 3150) $PN DG36
J 0
(-2940 3160);
DISPLAY 0.617021 (-2940 3160);
PAINT ORANGE (-2940 3160);
FORCEPROP 2 LASTPIN (-2950 3100) $PN DG64
J 0
(-2940 3110);
DISPLAY 0.617021 (-2940 3110);
PAINT ORANGE (-2940 3110);
FORCEPROP 2 LASTPIN (-2950 3050) $PN DH65
J 0
(-2940 3060);
DISPLAY 0.617021 (-2940 3060);
PAINT ORANGE (-2940 3060);
FORCEPROP 2 LASTPIN (-2950 3000) $PN DJ36
J 0
(-2940 3010);
DISPLAY 0.617021 (-2940 3010);
PAINT ORANGE (-2940 3010);
FORCEPROP 2 LASTPIN (-2950 2950) $PN DJ66
J 0
(-2940 2960);
DISPLAY 0.617021 (-2940 2960);
PAINT ORANGE (-2940 2960);
FORCEPROP 2 LASTPIN (-2950 2900) $PN DK15
J 0
(-2940 2910);
DISPLAY 0.617021 (-2940 2910);
PAINT ORANGE (-2940 2910);
FORCEPROP 2 LASTPIN (-2950 2850) $PN DK37
J 0
(-2940 2860);
DISPLAY 0.617021 (-2940 2860);
PAINT ORANGE (-2940 2860);
FORCEPROP 2 LASTPIN (-2950 2800) $PN DK65
J 0
(-2940 2810);
DISPLAY 0.617021 (-2940 2810);
PAINT ORANGE (-2940 2810);
FORCEPROP 2 LASTPIN (-2950 2750) $PN DK67
J 0
(-2940 2760);
DISPLAY 0.617021 (-2940 2760);
PAINT ORANGE (-2940 2760);
FORCEPROP 2 LASTPIN (-2950 2700) $PN DL38
J 0
(-2940 2710);
DISPLAY 0.617021 (-2940 2710);
PAINT ORANGE (-2940 2710);
FORCEPROP 2 LASTPIN (-2950 2650) $PN DL66
J 0
(-2940 2660);
DISPLAY 0.617021 (-2940 2660);
PAINT ORANGE (-2940 2660);
FORCEPROP 2 LASTPIN (-2950 2600) $PN DM67
J 0
(-2940 2610);
DISPLAY 0.617021 (-2940 2610);
PAINT ORANGE (-2940 2610);
FORCEPROP 2 LASTPIN (-2950 2550) $PN DN62
J 0
(-2940 2560);
DISPLAY 0.617021 (-2940 2560);
PAINT ORANGE (-2940 2560);
FORCEPROP 2 LASTPIN (-2950 2500) $PN DN66
J 0
(-2940 2510);
DISPLAY 0.617021 (-2940 2510);
PAINT ORANGE (-2940 2510);
FORCEPROP 2 LASTPIN (-2950 2450) $PN DP17
J 0
(-2940 2460);
DISPLAY 0.617021 (-2940 2460);
PAINT ORANGE (-2940 2460);
FORCEPROP 2 LASTPIN (-2950 2400) $PN DP65
J 0
(-2940 2410);
DISPLAY 0.617021 (-2940 2410);
PAINT ORANGE (-2940 2410);
FORCEPROP 2 LASTPIN (-2950 2350) $PN DR44
J 0
(-2940 2360);
DISPLAY 0.617021 (-2940 2360);
PAINT ORANGE (-2940 2360);
FORCEPROP 2 LASTPIN (-2950 2300) $PN DT71
J 0
(-2940 2310);
DISPLAY 0.617021 (-2940 2310);
PAINT ORANGE (-2940 2310);
FORCEPROP 2 LASTPIN (-2950 2250) $PN DU44
J 0
(-2940 2260);
DISPLAY 0.617021 (-2940 2260);
PAINT ORANGE (-2940 2260);
FORCEPROP 2 LASTPIN (-2950 2200) $PN DV61
J 0
(-2940 2210);
DISPLAY 0.617021 (-2940 2210);
PAINT ORANGE (-2940 2210);
FORCEPROP 2 LASTPIN (-2950 2150) $PN DV71
J 0
(-2940 2160);
DISPLAY 0.617021 (-2940 2160);
PAINT ORANGE (-2940 2160);
FORCEPROP 2 LASTPIN (-2950 2100) $PN DW44
J 0
(-2940 2110);
DISPLAY 0.617021 (-2940 2110);
PAINT ORANGE (-2940 2110);
FORCEPROP 2 LASTPIN (-2950 2050) $PN DW46
J 0
(-2940 2060);
DISPLAY 0.617021 (-2940 2060);
PAINT ORANGE (-2940 2060);
FORCEPROP 2 LASTPIN (-2950 2000) $PN DY3
J 0
(-2940 2010);
DISPLAY 0.617021 (-2940 2010);
PAINT ORANGE (-2940 2010);
FORCEPROP 2 LASTPIN (-2950 1950) $PN EA4
J 0
(-2940 1960);
DISPLAY 0.617021 (-2940 1960);
PAINT ORANGE (-2940 1960);
FORCEPROP 2 LASTPIN (-2950 1900) $PN EA44
J 0
(-2940 1910);
DISPLAY 0.617021 (-2940 1910);
PAINT ORANGE (-2940 1910);
FORCEPROP 2 LASTPIN (-2950 1850) $PN EB3
J 0
(-2940 1860);
DISPLAY 0.617021 (-2940 1860);
PAINT ORANGE (-2940 1860);
FORCEPROP 2 LASTPIN (-2950 1800) $PN EB5
J 0
(-2940 1810);
DISPLAY 0.617021 (-2940 1810);
PAINT ORANGE (-2940 1810);
FORCEPROP 2 LASTPIN (-2950 1750) $PN EB85
J 0
(-2940 1760);
DISPLAY 0.617021 (-2940 1760);
PAINT ORANGE (-2940 1760);
FORCEPROP 2 LASTPIN (-2950 1700) $PN EC16
J 0
(-2940 1710);
DISPLAY 0.617021 (-2940 1710);
PAINT ORANGE (-2940 1710);
FORCEPROP 2 LASTPIN (-2950 1650) $PN EC4
J 0
(-2940 1660);
DISPLAY 0.617021 (-2940 1660);
PAINT ORANGE (-2940 1660);
FORCEPROP 2 LASTPIN (-2950 1600) $PN EC44
J 0
(-2940 1610);
DISPLAY 0.617021 (-2940 1610);
PAINT ORANGE (-2940 1610);
FORCEPROP 2 LASTPIN (-2950 1550) $PN EC84
J 0
(-2940 1560);
DISPLAY 0.617021 (-2940 1560);
PAINT ORANGE (-2940 1560);
FORCEPROP 2 LASTPIN (-2950 1500) $PN ED45
J 0
(-2940 1510);
DISPLAY 0.617021 (-2940 1510);
PAINT ORANGE (-2940 1510);
FORCEPROP 2 LASTPIN (-2950 1450) $PN ED5
J 0
(-2940 1460);
DISPLAY 0.617021 (-2940 1460);
PAINT ORANGE (-2940 1460);
FORCEPROP 2 LASTPIN (-2950 1400) $PN ED83
J 0
(-2940 1410);
DISPLAY 0.617021 (-2940 1410);
PAINT ORANGE (-2940 1410);
FORCEPROP 2 LASTPIN (-2950 1350) $PN EE16
J 0
(-2940 1360);
DISPLAY 0.617021 (-2940 1360);
PAINT ORANGE (-2940 1360);
FORCEPROP 2 LASTPIN (-2950 1300) $PN EE46
J 0
(-2940 1310);
DISPLAY 0.617021 (-2940 1310);
PAINT ORANGE (-2940 1310);
FORCEPROP 2 LASTPIN (-2950 1250) $PN EE6
J 0
(-2940 1260);
DISPLAY 0.617021 (-2940 1260);
PAINT ORANGE (-2940 1260);
FORCEPROP 2 LASTPIN (-2950 1200) $PN EE82
J 0
(-2940 1210);
DISPLAY 0.617021 (-2940 1210);
PAINT ORANGE (-2940 1210);
FORCEPROP 2 LASTPIN (-2950 1150) $PN EE84
J 0
(-2940 1160);
DISPLAY 0.617021 (-2940 1160);
PAINT ORANGE (-2940 1160);
FORCEPROP 2 LASTPIN (-2950 1100) $PN EF47
J 0
(-2940 1110);
DISPLAY 0.617021 (-2940 1110);
PAINT ORANGE (-2940 1110);
FORCEPROP 2 LASTPIN (-2950 1050) $PN EF77
J 0
(-2940 1060);
DISPLAY 0.617021 (-2940 1060);
PAINT ORANGE (-2940 1060);
FORCEPROP 2 LASTPIN (-2950 1000) $PN EF81
J 0
(-2940 1010);
DISPLAY 0.617021 (-2940 1010);
PAINT ORANGE (-2940 1010);
FORCEPROP 2 LASTPIN (-2950 950) $PN EF83
J 0
(-2940 960);
DISPLAY 0.617021 (-2940 960);
PAINT ORANGE (-2940 960);
FORCEPROP 2 LASTPIN (-5050 2300) $PN BL16
J 2
(-5060 2310);
DISPLAY 0.617021 (-5060 2310);
PAINT ORANGE (-5060 2310);
FORCEPROP 2 LASTPIN (-5050 2200) $PN BT17
J 2
(-5060 2210);
DISPLAY 0.617021 (-5060 2210);
PAINT ORANGE (-5060 2210);
FORCEPROP 2 LASTPIN (-5050 2150) $PN BU16
J 2
(-5060 2160);
DISPLAY 0.617021 (-5060 2160);
PAINT ORANGE (-5060 2160);
FORCEPROP 2 LASTPIN (-5050 2350) $PN BN16
J 2
(-5060 2360);
DISPLAY 0.617021 (-5060 2360);
PAINT ORANGE (-5060 2360);
FORCEPROP 1 LAST PACK_TYPE BGA1
J 0
(-5000 4250);
PAINT SKYBLUE (-5000 4250);
DISPLAY INVISIBLE (-5000 4250);
FORCEPROP 2 LAST SEC_TYPE BGA1
J 0
(-5000 4250);
DISPLAY 1.021277 (-5000 4250);
PAINT ORANGE (-5000 4250);
DISPLAY INVISIBLE (-5000 4250);
FORCEPROP 2 LAST CDS_LIB chpset_lib
J 0
(-4000 2550);
PAINT ORANGE (-4000 2550);
DISPLAY INVISIBLE (-4000 2550);
FORCEPROP 2 LAST SEC 22
J 0
(-5000 4250);
DISPLAY 0.680851 (-5000 4250);
PAINT MONO (-5000 4250);
DISPLAY INVISIBLE (-5000 4250);
FORCEPROP 2 LAST CDS_LOCATION U2D1
J 0
(-5000 4200);
DISPLAY 0.617021 (-5000 4200);
PAINT AQUA (-5000 4200);
DISPLAY INVISIBLE (-5000 4200);
FORCEPROP 1 LAST PATH I107
J 0
(-4000 4150);
PAINT GREEN (-4000 4150);
DISPLAY INVISIBLE (-4000 4150);
FORCEADD VCC_CORE..1
(-5925 2950);
FORCEPROP 3 LASTPIN (-5925 2900) SIG_NAME PVCCMCP_CPU1\g
J 0
(-5915 2910);
DISPLAY 0.659574 (-5915 2910);
PAINT MONO (-5915 2910);
DISPLAY INVISIBLE (-5915 2910);
FORCEPROP 1 LAST HDL_POWER PVCCMCP_CPU1
J 1
(-5925 3000);
DISPLAY 0.617021 (-5925 3000);
PAINT GREEN (-5925 3000);
FORCEPROP 2 LAST CDS_LIB mstr_symbols
J 0
(-5925 2950);
PAINT ORANGE (-5925 2950);
DISPLAY INVISIBLE (-5925 2950);
FORCEPROP 1 LAST PATH I108
J 0
(-5875 2975);
DISPLAY 0.872340 (-5875 2975);
PAINT AQUA (-5875 2975);
DISPLAY INVISIBLE (-5875 2975);
FORCEADD OFFPAGE..1
(-6125 1900);
FORCEPROP 2 LAST $XR0 97 
J 0
(-6346 1900);
DISPLAY 0.638298 (-6346 1900);
PAINT MONO (-6346 1900);
FORCEPROP 2 LAST CDS_LIB mstr_standard
J 0
(-6125 1900);
PAINT ORANGE (-6125 1900);
DISPLAY INVISIBLE (-6125 1900);
FORCEPROP 1 LAST OFFPAGE TRUE
J 0
(-5800 1775);
DISPLAY 0.872340 (-5800 1775);
PAINT GREEN (-5800 1775);
DISPLAY INVISIBLE (-5800 1775);
FORCEPROP 1 LAST COMMENT_BODY TRUE
J 0
(-6000 1800);
DISPLAY 0.872340 (-6000 1800);
PAINT GREEN (-6000 1800);
DISPLAY INVISIBLE (-6000 1800);
FORCEPROP 2 LAST PATH I109
J 0
(-6075 1975);
DISPLAY 1.021277 (-6075 1975);
PAINT ORANGE (-6075 1975);
DISPLAY INVISIBLE (-6075 1975);
FORCEADD PVCCIO_CPU1..1
(-5350 4425);
FORCEPROP 3 LASTPIN (-5350 4375) SIG_NAME PVCCIO_CPU1\g
J 0
(-5340 4385);
DISPLAY 0.659574 (-5340 4385);
PAINT MONO (-5340 4385);
DISPLAY INVISIBLE (-5340 4385);
FORCEPROP 1 LAST VOLTAGE 1.1V
J 0
(-5395 4382);
DISPLAY 0.340426 (-5395 4382);
PAINT SKYBLUE (-5395 4382);
DISPLAY INVISIBLE (-5395 4382);
FORCEPROP 2 LAST CDS_LIB mstr_symbols
J 0
(-5350 4425);
PAINT ORANGE (-5350 4425);
DISPLAY INVISIBLE (-5350 4425);
FORCEPROP 1 LAST BODY_TYPE PLUMBING
J 0
(-5395 4382);
DISPLAY 0.340426 (-5395 4382);
PAINT GREEN (-5395 4382);
DISPLAY INVISIBLE (-5395 4382);
FORCEPROP 1 LAST PATH I22
J 0
(-5300 4450);
DISPLAY 0.872340 (-5300 4450);
PAINT AQUA (-5300 4450);
DISPLAY INVISIBLE (-5300 4450);
FORCEPROP 1 LAST HDL_POWER PVCCIO_CPU1
J 1
(-5350 4475);
DISPLAY 0.872340 (-5350 4475);
PAINT GREEN (-5350 4475);
DISPLAY INVISIBLE (-5350 4475);
FORCEADD OFFPAGE..5
(-6125 2500);
FORCEPROP 2 LAST $XR0 210 
J 0
(-6380 2500);
DISPLAY 0.638298 (-6380 2500);
PAINT MONO (-6380 2500);
FORCEPROP 2 LAST CDS_LIB mstr_standard
J 0
(-6125 2500);
DISPLAY 0.489362 (-6125 2500);
PAINT ORANGE (-6125 2500);
DISPLAY INVISIBLE (-6125 2500);
FORCEPROP 1 LAST OFFPAGE TRUE
J 0
(-5800 2375);
DISPLAY 0.680851 (-5800 2375);
PAINT GREEN (-5800 2375);
DISPLAY INVISIBLE (-5800 2375);
FORCEPROP 1 LAST COMMENT_BODY TRUE
J 0
(-6025 2425);
DISPLAY 0.680851 (-6025 2425);
PAINT PEACH (-6025 2425);
DISPLAY INVISIBLE (-6025 2425);
FORCEPROP 2 LAST PATH I91
J 0
(-6375 2550);
DISPLAY 1.021277 (-6375 2550);
PAINT ORANGE (-6375 2550);
DISPLAY INVISIBLE (-6375 2550);
FORCEADD OFFPAGE..5
(-6125 2450);
FORCEPROP 2 LAST $XR0 210 
J 0
(-6380 2450);
DISPLAY 0.638298 (-6380 2450);
PAINT MONO (-6380 2450);
FORCEPROP 2 LAST CDS_LIB mstr_standard
J 0
(-6125 2450);
DISPLAY 0.489362 (-6125 2450);
PAINT ORANGE (-6125 2450);
DISPLAY INVISIBLE (-6125 2450);
FORCEPROP 1 LAST OFFPAGE TRUE
J 0
(-5800 2325);
DISPLAY 0.680851 (-5800 2325);
PAINT GREEN (-5800 2325);
DISPLAY INVISIBLE (-5800 2325);
FORCEPROP 1 LAST COMMENT_BODY TRUE
J 0
(-6025 2375);
DISPLAY 0.680851 (-6025 2375);
PAINT PEACH (-6025 2375);
DISPLAY INVISIBLE (-6025 2375);
FORCEPROP 2 LAST PATH I92
J 0
(-6375 2500);
DISPLAY 1.021277 (-6375 2500);
PAINT ORANGE (-6375 2500);
DISPLAY INVISIBLE (-6375 2500);
FORCEADD OFFPAGE..5
(-6125 2350);
FORCEPROP 2 LAST $XR0 193 
J 0
(-6380 2350);
DISPLAY 0.638298 (-6380 2350);
PAINT MONO (-6380 2350);
FORCEPROP 2 LAST CDS_LIB mstr_standard
J 0
(-6125 2350);
DISPLAY 0.489362 (-6125 2350);
PAINT ORANGE (-6125 2350);
DISPLAY INVISIBLE (-6125 2350);
FORCEPROP 1 LAST OFFPAGE TRUE
J 0
(-5800 2225);
DISPLAY 0.680851 (-5800 2225);
PAINT GREEN (-5800 2225);
DISPLAY INVISIBLE (-5800 2225);
FORCEPROP 1 LAST COMMENT_BODY TRUE
J 0
(-6025 2275);
DISPLAY 0.680851 (-6025 2275);
PAINT PEACH (-6025 2275);
DISPLAY INVISIBLE (-6025 2275);
FORCEPROP 2 LAST PATH I93
J 0
(-6375 2400);
DISPLAY 1.021277 (-6375 2400);
PAINT ORANGE (-6375 2400);
DISPLAY INVISIBLE (-6375 2400);
FORCEADD OFFPAGE..5
(-6125 2300);
FORCEPROP 2 LAST $XR0 193 
J 0
(-6380 2300);
DISPLAY 0.638298 (-6380 2300);
PAINT MONO (-6380 2300);
FORCEPROP 2 LAST CDS_LIB mstr_standard
J 0
(-6125 2300);
DISPLAY 0.489362 (-6125 2300);
PAINT ORANGE (-6125 2300);
DISPLAY INVISIBLE (-6125 2300);
FORCEPROP 1 LAST OFFPAGE TRUE
J 0
(-5800 2175);
DISPLAY 0.680851 (-5800 2175);
PAINT GREEN (-5800 2175);
DISPLAY INVISIBLE (-5800 2175);
FORCEPROP 1 LAST COMMENT_BODY TRUE
J 0
(-6025 2225);
DISPLAY 0.680851 (-6025 2225);
PAINT PEACH (-6025 2225);
DISPLAY INVISIBLE (-6025 2225);
FORCEPROP 2 LAST PATH I94
J 0
(-6375 2350);
DISPLAY 1.021277 (-6375 2350);
PAINT ORANGE (-6375 2350);
DISPLAY INVISIBLE (-6375 2350);
FORCEADD OFFPAGE..5
(-6125 2200);
FORCEPROP 2 LAST $XR0 193 
J 0
(-6380 2200);
DISPLAY 0.638298 (-6380 2200);
PAINT MONO (-6380 2200);
FORCEPROP 2 LAST CDS_LIB mstr_standard
J 0
(-6125 2200);
DISPLAY 0.489362 (-6125 2200);
PAINT ORANGE (-6125 2200);
DISPLAY INVISIBLE (-6125 2200);
FORCEPROP 1 LAST OFFPAGE TRUE
J 0
(-5800 2075);
DISPLAY 0.680851 (-5800 2075);
PAINT GREEN (-5800 2075);
DISPLAY INVISIBLE (-5800 2075);
FORCEPROP 1 LAST COMMENT_BODY TRUE
J 0
(-6025 2125);
DISPLAY 0.680851 (-6025 2125);
PAINT PEACH (-6025 2125);
DISPLAY INVISIBLE (-6025 2125);
FORCEPROP 2 LAST PATH I95
J 0
(-6375 2250);
DISPLAY 1.021277 (-6375 2250);
PAINT ORANGE (-6375 2250);
DISPLAY INVISIBLE (-6375 2250);
FORCEADD OFFPAGE..5
(-6125 2150);
FORCEPROP 2 LAST $XR0 193 
J 0
(-6380 2150);
DISPLAY 0.638298 (-6380 2150);
PAINT MONO (-6380 2150);
FORCEPROP 2 LAST CDS_LIB mstr_standard
J 0
(-6125 2150);
DISPLAY 0.489362 (-6125 2150);
PAINT ORANGE (-6125 2150);
DISPLAY INVISIBLE (-6125 2150);
FORCEPROP 1 LAST OFFPAGE TRUE
J 0
(-5800 2025);
DISPLAY 0.680851 (-5800 2025);
PAINT GREEN (-5800 2025);
DISPLAY INVISIBLE (-5800 2025);
FORCEPROP 1 LAST COMMENT_BODY TRUE
J 0
(-6025 2075);
DISPLAY 0.680851 (-6025 2075);
PAINT PEACH (-6025 2075);
DISPLAY INVISIBLE (-6025 2075);
FORCEPROP 2 LAST PATH I96
J 0
(-6375 2200);
DISPLAY 1.021277 (-6375 2200);
PAINT ORANGE (-6375 2200);
DISPLAY INVISIBLE (-6375 2200);
FORCEADD OFFPAGE..5
(-6125 2000);
FORCEPROP 2 LAST $XR0 214 
J 0
(-6380 2000);
DISPLAY 0.638298 (-6380 2000);
PAINT MONO (-6380 2000);
FORCEPROP 2 LAST CDS_LIB mstr_standard
J 0
(-6125 2000);
DISPLAY 0.489362 (-6125 2000);
PAINT ORANGE (-6125 2000);
DISPLAY INVISIBLE (-6125 2000);
FORCEPROP 1 LAST OFFPAGE TRUE
J 0
(-5800 1875);
DISPLAY 0.680851 (-5800 1875);
PAINT GREEN (-5800 1875);
DISPLAY INVISIBLE (-5800 1875);
FORCEPROP 1 LAST COMMENT_BODY TRUE
J 0
(-6025 1925);
DISPLAY 0.680851 (-6025 1925);
PAINT PEACH (-6025 1925);
DISPLAY INVISIBLE (-6025 1925);
FORCEPROP 2 LAST PATH I97
J 0
(-6375 2050);
DISPLAY 1.021277 (-6375 2050);
PAINT ORANGE (-6375 2050);
DISPLAY INVISIBLE (-6375 2050);
FORCEADD OFFPAGE..5
(-6125 2050);
FORCEPROP 2 LAST $XR0 214 
J 0
(-6380 2050);
DISPLAY 0.638298 (-6380 2050);
PAINT MONO (-6380 2050);
FORCEPROP 2 LAST CDS_LIB mstr_standard
J 0
(-6125 2050);
DISPLAY 0.489362 (-6125 2050);
PAINT ORANGE (-6125 2050);
DISPLAY INVISIBLE (-6125 2050);
FORCEPROP 1 LAST OFFPAGE TRUE
J 0
(-5800 1925);
DISPLAY 0.680851 (-5800 1925);
PAINT GREEN (-5800 1925);
DISPLAY INVISIBLE (-5800 1925);
FORCEPROP 1 LAST COMMENT_BODY TRUE
J 0
(-6025 1975);
DISPLAY 0.680851 (-6025 1975);
PAINT PEACH (-6025 1975);
DISPLAY INVISIBLE (-6025 1975);
FORCEPROP 2 LAST PATH I98
J 0
(-6375 2100);
DISPLAY 1.021277 (-6375 2100);
PAINT ORANGE (-6375 2100);
DISPLAY INVISIBLE (-6375 2100);
FORCEADD PRELIM..10
(-3990 2615);
PAINT GRAY (-3990 2615);
FORCEPROP 2 LAST CDS_LIB mstr_misc
J 0
(-3990 2615);
PAINT ORANGE (-3990 2615);
DISPLAY INVISIBLE (-3990 2615);
FORCEPROP 1 LAST COMMENT_BODY TRUE
J 0
(-3990 2615);
PAINT ORANGE (-3990 2615);
DISPLAY INVISIBLE (-3990 2615);
FORCEADD DESIGN_NOTE..1
(-4825 575);
FORCEPROP 0 LAST L1 CPU SYMBOLS 1-30 ARE PRELIMINARY AND SUBJECT TO CHANGE
J 0
(-5025 450);
DISPLAY 1.021277 (-5025 450);
PAINT ORANGE (-5025 450);
FORCEPROP 2 LAST CDS_LIB mstr_symbols
J 0
(-4825 575);
PAINT ORANGE (-4825 575);
DISPLAY INVISIBLE (-4825 575);
FORCEPROP 1 LAST COMMENT_BODY TRUE
J 0
(-4800 675);
DISPLAY 0.978723 (-4800 675);
PAINT ORANGE (-4800 675);
DISPLAY INVISIBLE (-4800 675);
FORCEADD INTEL_CORP_BPAGE..1
(0 0);
FORCEPROP 1 LAST CDS_CON_LAST_MODIFIED Tue Dec 01 11:51:39 2015
J 0
(-1425 325);
DISPLAY 1.340426 (-1425 325);
PAINT GREEN (-1425 325);
DISPLAY INVISIBLE (-1425 325);
FORCEPROP 1 LAST CUSTOM_TXT_CDS <CURRENT_DESIGN_SHEET> OF <TOTAL_DESIGN_SHEETS>
J 0
(-500 25);
PAINT GREEN (-500 25);
FORCEPROP 1 LAST CUSTOM_TXT_CDS <CON_LAST_MODIFIED>
J 0
(-1925 350);
PAINT GREEN (-1925 350);
FORCEPROP 2 LAST CUSTOM_TXT_CDS <XR_PAGE_TITLE>
J 0
(-7890 5250);
DISPLAY 0.638298 (-7890 5250);
PAINT PINK (-7890 5250);
DISPLAY INVISIBLE (-7890 5250);
FORCEPROP 1 LAST SCH_ADDRESS3 Santa Clara, CA 95052-8119
J 0
(-3975 25);
DISPLAY 0.617021 (-3975 25);
PAINT GREEN (-3975 25);
FORCEPROP 1 LAST SCH_ADDRESS2 P.O. BOX 58119
J 0
(-3975 75);
DISPLAY 0.617021 (-3975 75);
PAINT GREEN (-3975 75);
FORCEPROP 1 LAST SCH_ADDRESS1 2200 Mission College Blvd.
J 0
(-3975 125);
DISPLAY 0.617021 (-3975 125);
PAINT GREEN (-3975 125);
FORCEPROP 1 LAST SCH_TITLE SKYLAKE - SKT1 - 19 OF 21
J 0
(-7950 50);
DISPLAY 1.212766 (-7950 50);
PAINT GREEN (-7950 50);
FORCEPROP 1 LAST SCH_NUMBER H4694802
J 0
(-1300 150);
DISPLAY 1.212766 (-1300 150);
PAINT YELLOW (-1300 150);
FORCEPROP 1 LAST SCH_DEPT BESD
J 1
(-4450 100);
DISPLAY 1.212766 (-4450 100);
PAINT YELLOW (-4450 100);
FORCEPROP 1 LAST SCH_REV 2.420
J 0
(-250 150);
DISPLAY 0.978723 (-250 150);
PAINT YELLOW (-250 150);
FORCEPROP 2 LAST PAGE_BORDER TRUE
J 0
(-7890 5250);
DISPLAY 0.851064 (-7890 5250);
PAINT PINK (-7890 5250);
DISPLAY INVISIBLE (-7890 5250);
FORCEPROP 2 LAST CDS_LIB mstr_symbols
J 0
(0 0);
PAINT ORANGE (0 0);
DISPLAY INVISIBLE (0 0);
FORCEPROP 1 LAST COMMENT_BODY TRUE
J 0
(12 12);
DISPLAY 0.638298 (12 12);
PAINT GREEN (12 12);
DISPLAY INVISIBLE (12 12);
FORCEPROP 2 LAST CDS_XR_PAGE_TITLE CR-73 : @BASEBOARD_FAB2_LIB.BASEBOARD_FAB2(SCH_1):PAGE73
J 0
(-7890 5250);
DISPLAY 0.638298 (-7890 5250);
PAINT PINK (-7890 5250);
DISPLAY INVISIBLE (-7890 5250);
WIRE 16 -1 (-2950 3550)(-1800 3550);
WIRE 16 -1 (-1800 3550)(-1800 3850);
WIRE 16 -1 (-2950 3850)(-1800 3850);
WIRE 16 -1 (-1800 4050)(-1800 3850);
WIRE 16 -1 (-5225 1250)(-5050 1250);
WIRE 16 -1 (-5225 1400)(-5225 1250);
WIRE 16 -1 (-5225 1400)(-5050 1400);
WIRE 16 -1 (-5225 1400)(-5225 1550);
WIRE 16 -1 (-5225 1550)(-5050 1550);
WIRE 16 -1 (-5225 1550)(-5225 1700);
WIRE 16 -1 (-5225 1700)(-5050 1700);
WIRE 16 -1 (-5225 1700)(-5225 1850);
WIRE 16 -1 (-5225 1850)(-5050 1850);
WIRE 16 -1 (-6600 1850)(-5225 1850);
WIRE 16 -1 (-6600 1925)(-6600 1850);
WIRE 16 -1 (-5050 2600)(-5250 2600);
WIRE 16 -1 (-5250 2600)(-5250 2700);
WIRE 16 -1 (-5050 2700)(-5250 2700);
WIRE 16 -1 (-5250 2700)(-5250 2750);
WIRE 16 -1 (-5050 2750)(-5250 2750);
WIRE 16 -1 (-5250 2750)(-5250 2800);
WIRE 16 -1 (-5050 2800)(-5250 2800);
WIRE 16 -1 (-5250 2800)(-5925 2800);
WIRE 16 -1 (-5925 2800)(-5925 2900);
WIRE 16 -1 (-5050 2900)(-5350 2900);
WIRE 16 -1 (-5350 2950)(-5350 2900);
WIRE 16 -1 (-5050 2950)(-5350 2950);
WIRE 16 -1 (-5350 3000)(-5350 2950);
WIRE 16 -1 (-5050 3000)(-5350 3000);
WIRE 16 -1 (-5350 3050)(-5350 3000);
WIRE 16 -1 (-5050 3050)(-5350 3050);
WIRE 16 -1 (-5350 3100)(-5350 3050);
WIRE 16 -1 (-5050 3100)(-5350 3100);
WIRE 16 -1 (-5350 3150)(-5350 3100);
WIRE 16 -1 (-5050 3150)(-5350 3150);
WIRE 16 -1 (-5350 3150)(-5350 3200);
WIRE 16 -1 (-5050 3200)(-5350 3200);
WIRE 16 -1 (-5350 3200)(-5350 3250);
WIRE 16 -1 (-5050 3250)(-5350 3250);
WIRE 16 -1 (-5350 3250)(-5350 3300);
WIRE 16 -1 (-5050 3300)(-5350 3300);
WIRE 16 -1 (-5350 3300)(-5350 3350);
WIRE 16 -1 (-5050 3350)(-5350 3350);
WIRE 16 -1 (-5350 3350)(-5350 3450);
WIRE 16 -1 (-5050 3450)(-5350 3450);
WIRE 16 -1 (-5350 3450)(-5350 3500);
WIRE 16 -1 (-5050 3500)(-5350 3500);
WIRE 16 -1 (-5350 3500)(-5350 3550);
WIRE 16 -1 (-5050 3550)(-5350 3550);
WIRE 16 -1 (-5350 3550)(-5350 3600);
WIRE 16 -1 (-5050 3600)(-5350 3600);
WIRE 16 -1 (-5350 3600)(-5350 3650);
WIRE 16 -1 (-5050 3650)(-5350 3650);
WIRE 16 -1 (-5350 3650)(-5350 3700);
WIRE 16 -1 (-5050 3700)(-5350 3700);
WIRE 16 -1 (-5350 3700)(-5350 3750);
WIRE 16 -1 (-5050 3750)(-5350 3750);
WIRE 16 -1 (-5350 3750)(-5350 3800);
WIRE 16 -1 (-5050 3800)(-5350 3800);
WIRE 16 -1 (-5350 3800)(-5350 3900);
WIRE 16 -1 (-5050 3900)(-5350 3900);
WIRE 16 -1 (-5350 3900)(-5350 3950);
WIRE 16 -1 (-5050 3950)(-5350 3950);
WIRE 16 -1 (-5350 3950)(-5350 4375);
WIRE 16 -1 (-5050 1200)(-5775 1200);
FORCEPROP 0 LAST SIG_NAME TP_CPU1_RSVD_61
J 0
(-5785 1210);
DISPLAY 0.617021 (-5785 1210);
PAINT ORANGE (-5785 1210);
FORCEPROP 2 LASTPROP $XRERR UNIQUE?
J 0
(-6015 1200);
DISPLAY 0.638298 (-6015 1200);
PAINT MONO (-6015 1200);
DISPLAY INVISIBLE (-6015 1200);
WIRE 16 -1 (-5050 1300)(-5775 1300);
FORCEPROP 0 LAST SIG_NAME TP_CPU1_KTI2_DFX_DN
J 0
(-5773 1318);
DISPLAY 0.617021 (-5773 1318);
PAINT ORANGE (-5773 1318);
FORCEPROP 2 LASTPROP $XRERR UNIQUE?
J 0
(-6015 1300);
DISPLAY 0.638298 (-6015 1300);
PAINT MONO (-6015 1300);
DISPLAY INVISIBLE (-6015 1300);
WIRE 16 -1 (-5050 1350)(-5775 1350);
FORCEPROP 0 LAST SIG_NAME TP_CPU1_RSVD_64
J 0
(-5760 1360);
DISPLAY 0.617021 (-5760 1360);
PAINT ORANGE (-5760 1360);
FORCEPROP 2 LASTPROP $XRERR UNIQUE?
J 0
(-6015 1350);
DISPLAY 0.638298 (-6015 1350);
PAINT MONO (-6015 1350);
DISPLAY INVISIBLE (-6015 1350);
WIRE 16 -1 (-5050 1450)(-5775 1450);
FORCEPROP 0 LAST SIG_NAME TP_CPU1_RSVD_66
J 0
(-5785 1460);
DISPLAY 0.617021 (-5785 1460);
PAINT ORANGE (-5785 1460);
FORCEPROP 2 LASTPROP $XRERR UNIQUE?
J 0
(-6015 1450);
DISPLAY 0.638298 (-6015 1450);
PAINT MONO (-6015 1450);
DISPLAY INVISIBLE (-6015 1450);
WIRE 16 -1 (-5050 1500)(-5775 1500);
FORCEPROP 0 LAST SIG_NAME TP_CPU1_RSVD_67
J 0
(-5785 1510);
DISPLAY 0.617021 (-5785 1510);
PAINT ORANGE (-5785 1510);
FORCEPROP 2 LASTPROP $XRERR UNIQUE?
J 0
(-6015 1500);
DISPLAY 0.638298 (-6015 1500);
PAINT MONO (-6015 1500);
DISPLAY INVISIBLE (-6015 1500);
WIRE 16 -1 (-5050 1600)(-5775 1600);
FORCEPROP 0 LAST SIG_NAME TP_CPU1_RSVD_69
J 0
(-5760 1610);
DISPLAY 0.617021 (-5760 1610);
PAINT ORANGE (-5760 1610);
FORCEPROP 2 LASTPROP $XRERR UNIQUE?
J 0
(-6015 1600);
DISPLAY 0.638298 (-6015 1600);
PAINT MONO (-6015 1600);
DISPLAY INVISIBLE (-6015 1600);
WIRE 16 -1 (-5050 1650)(-5775 1650);
FORCEPROP 0 LAST SIG_NAME TP_CPU1_RSVD_70
J 0
(-5760 1660);
DISPLAY 0.617021 (-5760 1660);
PAINT ORANGE (-5760 1660);
FORCEPROP 2 LASTPROP $XRERR UNIQUE?
J 0
(-6015 1650);
DISPLAY 0.638298 (-6015 1650);
PAINT MONO (-6015 1650);
DISPLAY INVISIBLE (-6015 1650);
WIRE 16 -1 (-5050 1750)(-5775 1750);
FORCEPROP 0 LAST SIG_NAME TP_CPU1_RSVD_72
J 0
(-5760 1760);
DISPLAY 0.617021 (-5760 1760);
PAINT ORANGE (-5760 1760);
FORCEPROP 2 LASTPROP $XRERR UNIQUE?
J 0
(-6015 1750);
DISPLAY 0.638298 (-6015 1750);
PAINT MONO (-6015 1750);
DISPLAY INVISIBLE (-6015 1750);
WIRE 16 -1 (-5050 1800)(-5775 1800);
FORCEPROP 0 LAST SIG_NAME TP_CPU1_RSVD_73
J 0
(-5760 1810);
DISPLAY 0.617021 (-5760 1810);
PAINT ORANGE (-5760 1810);
FORCEPROP 2 LASTPROP $XRERR UNIQUE?
J 0
(-6015 1800);
DISPLAY 0.638298 (-6015 1800);
PAINT MONO (-6015 1800);
DISPLAY INVISIBLE (-6015 1800);
WIRE 16 -1 (-5050 1900)(-6075 1900);
FORCEPROP 0 LAST SIG_NAME PD_CPU1_MCP01_DMON
J 0
(-6035 1910);
DISPLAY 0.617021 (-6035 1910);
PAINT ORANGE (-6035 1910);
WIRE 16 -1 (-5050 2000)(-6075 2000);
FORCEPROP 2 LAST SIG_NAME VSENSE_PVCCIO_CPU1_SKT_VRTN
J 0
(-6060 2010);
DISPLAY 0.617021 (-6060 2010);
PAINT ORANGE (-6060 2010);
WIRE 16 -1 (-5050 2650)(-5675 2650);
FORCEPROP 0 LAST SIG_NAME TP_CPU1_KTI2_AMONV
J 0
(-5685 2660);
DISPLAY 0.617021 (-5685 2660);
PAINT ORANGE (-5685 2660);
FORCEPROP 2 LASTPROP $XRERR UNIQUE?
J 0
(-5915 2650);
DISPLAY 0.638298 (-5915 2650);
PAINT MONO (-5915 2650);
DISPLAY INVISIBLE (-5915 2650);
WIRE 16 -1 (-5050 2500)(-6075 2500);
FORCEPROP 2 LAST SIG_NAME VSENSE_PVSA_CPU1_SKT_VSEN
J 0
(-6060 2510);
DISPLAY 0.617021 (-6060 2510);
PAINT ORANGE (-6060 2510);
WIRE 16 -1 (-5050 2450)(-6075 2450);
FORCEPROP 2 LAST SIG_NAME VSENSE_PVSA_CPU1_SKT_VRTN
J 0
(-6060 2460);
DISPLAY 0.617021 (-6060 2460);
PAINT ORANGE (-6060 2460);
WIRE 16 -1 (-5050 2350)(-6075 2350);
FORCEPROP 2 LAST SIG_NAME VSENSE_PVCCMCP_CPU1_SKT_VSEN
J 0
(-6060 2360);
DISPLAY 0.617021 (-6060 2360);
PAINT ORANGE (-6060 2360);
WIRE 16 -1 (-5050 2300)(-6075 2300);
FORCEPROP 2 LAST SIG_NAME VSENSE_PVCCMCP_CPU1_SKT_VRTN
J 0
(-6060 2310);
DISPLAY 0.617021 (-6060 2310);
PAINT ORANGE (-6060 2310);
WIRE 16 -1 (-5050 2200)(-6075 2200);
FORCEPROP 2 LAST SIG_NAME VSENSE_PVCCIOMCP_CPU1_SKT_VSEN
J 0
(-6060 2210);
DISPLAY 0.617021 (-6060 2210);
PAINT ORANGE (-6060 2210);
WIRE 16 -1 (-5050 2150)(-6075 2150);
FORCEPROP 2 LAST SIG_NAME VSENSE_PVCCIOMCP_CPU1_SKT_VRTN
J 0
(-6060 2160);
DISPLAY 0.617021 (-6060 2160);
PAINT ORANGE (-6060 2160);
WIRE 16 -1 (-5050 2050)(-6075 2050);
FORCEPROP 2 LAST SIG_NAME VSENSE_PVCCIO_CPU1_SKT_VSEN
J 0
(-6060 2060);
DISPLAY 0.617021 (-6060 2060);
PAINT ORANGE (-6060 2060);
WIRE 16 -1 (-2950 950)(-2350 950);
FORCEPROP 2 LAST SIG_NAME TP_CPU1_RSVD_0
J 0
(-2725 948);
DISPLAY 0.617021 (-2725 948);
PAINT ORANGE (-2725 948);
FORCEPROP 2 LASTPROP $XRERR UNIQUE?
J 0
(-2320 950);
DISPLAY 0.638298 (-2320 950);
PAINT MONO (-2320 950);
DISPLAY INVISIBLE (-2320 950);
WIRE 16 -1 (-2950 1000)(-2350 1000);
FORCEPROP 2 LAST SIG_NAME TP_CPU1_RSVD_1
J 0
(-2725 998);
DISPLAY 0.617021 (-2725 998);
PAINT ORANGE (-2725 998);
FORCEPROP 2 LASTPROP $XRERR UNIQUE?
J 0
(-2320 1000);
DISPLAY 0.638298 (-2320 1000);
PAINT MONO (-2320 1000);
DISPLAY INVISIBLE (-2320 1000);
WIRE 16 -1 (-2950 1050)(-2350 1050);
FORCEPROP 2 LAST SIG_NAME TP_CPU1_RSVD_2
J 0
(-2725 1048);
DISPLAY 0.617021 (-2725 1048);
PAINT ORANGE (-2725 1048);
FORCEPROP 2 LASTPROP $XRERR UNIQUE?
J 0
(-2320 1050);
DISPLAY 0.638298 (-2320 1050);
PAINT MONO (-2320 1050);
DISPLAY INVISIBLE (-2320 1050);
WIRE 16 -1 (-2950 1100)(-2350 1100);
FORCEPROP 2 LAST SIG_NAME TP_CPU1_RSVD_3
J 0
(-2725 1098);
DISPLAY 0.617021 (-2725 1098);
PAINT ORANGE (-2725 1098);
FORCEPROP 2 LASTPROP $XRERR UNIQUE?
J 0
(-2320 1100);
DISPLAY 0.638298 (-2320 1100);
PAINT MONO (-2320 1100);
DISPLAY INVISIBLE (-2320 1100);
WIRE 16 -1 (-2950 1150)(-2350 1150);
FORCEPROP 2 LAST SIG_NAME TP_CPU1_RSVD_4
J 0
(-2725 1148);
DISPLAY 0.617021 (-2725 1148);
PAINT ORANGE (-2725 1148);
FORCEPROP 2 LASTPROP $XRERR UNIQUE?
J 0
(-2320 1150);
DISPLAY 0.638298 (-2320 1150);
PAINT MONO (-2320 1150);
DISPLAY INVISIBLE (-2320 1150);
WIRE 16 -1 (-2950 1200)(-2350 1200);
FORCEPROP 2 LAST SIG_NAME TP_CPU1_RSVD_5
J 0
(-2725 1198);
DISPLAY 0.617021 (-2725 1198);
PAINT ORANGE (-2725 1198);
FORCEPROP 2 LASTPROP $XRERR UNIQUE?
J 0
(-2320 1200);
DISPLAY 0.638298 (-2320 1200);
PAINT MONO (-2320 1200);
DISPLAY INVISIBLE (-2320 1200);
WIRE 16 -1 (-2950 1250)(-2350 1250);
FORCEPROP 2 LAST SIG_NAME TP_CPU1_RSVD_6
J 0
(-2725 1248);
DISPLAY 0.617021 (-2725 1248);
PAINT ORANGE (-2725 1248);
FORCEPROP 2 LASTPROP $XRERR UNIQUE?
J 0
(-2320 1250);
DISPLAY 0.638298 (-2320 1250);
PAINT MONO (-2320 1250);
DISPLAY INVISIBLE (-2320 1250);
WIRE 16 -1 (-2950 1300)(-2350 1300);
FORCEPROP 2 LAST SIG_NAME TP_CPU1_RSVD_7
J 0
(-2725 1298);
DISPLAY 0.617021 (-2725 1298);
PAINT ORANGE (-2725 1298);
FORCEPROP 2 LASTPROP $XRERR UNIQUE?
J 0
(-2320 1300);
DISPLAY 0.638298 (-2320 1300);
PAINT MONO (-2320 1300);
DISPLAY INVISIBLE (-2320 1300);
WIRE 16 -1 (-2950 1350)(-2350 1350);
FORCEPROP 2 LAST SIG_NAME TP_CPU1_RSVD_8
J 0
(-2725 1348);
DISPLAY 0.617021 (-2725 1348);
PAINT ORANGE (-2725 1348);
FORCEPROP 2 LASTPROP $XRERR UNIQUE?
J 0
(-2320 1350);
DISPLAY 0.638298 (-2320 1350);
PAINT MONO (-2320 1350);
DISPLAY INVISIBLE (-2320 1350);
WIRE 16 -1 (-2950 1400)(-2350 1400);
FORCEPROP 2 LAST SIG_NAME TP_CPU1_RSVD_9
J 0
(-2725 1398);
DISPLAY 0.617021 (-2725 1398);
PAINT ORANGE (-2725 1398);
FORCEPROP 2 LASTPROP $XRERR UNIQUE?
J 0
(-2320 1400);
DISPLAY 0.638298 (-2320 1400);
PAINT MONO (-2320 1400);
DISPLAY INVISIBLE (-2320 1400);
WIRE 16 -1 (-2950 1450)(-2350 1450);
FORCEPROP 2 LAST SIG_NAME TP_CPU1_RSVD_10
J 0
(-2725 1448);
DISPLAY 0.617021 (-2725 1448);
PAINT ORANGE (-2725 1448);
FORCEPROP 2 LASTPROP $XRERR UNIQUE?
J 0
(-2320 1450);
DISPLAY 0.638298 (-2320 1450);
PAINT MONO (-2320 1450);
DISPLAY INVISIBLE (-2320 1450);
WIRE 16 -1 (-2950 1500)(-2350 1500);
FORCEPROP 2 LAST SIG_NAME TP_CPU1_RSVD_11
J 0
(-2725 1498);
DISPLAY 0.617021 (-2725 1498);
PAINT ORANGE (-2725 1498);
FORCEPROP 2 LASTPROP $XRERR UNIQUE?
J 0
(-2320 1500);
DISPLAY 0.638298 (-2320 1500);
PAINT MONO (-2320 1500);
DISPLAY INVISIBLE (-2320 1500);
WIRE 16 -1 (-2950 1550)(-2350 1550);
FORCEPROP 2 LAST SIG_NAME TP_CPU1_RSVD_12
J 0
(-2725 1548);
DISPLAY 0.617021 (-2725 1548);
PAINT ORANGE (-2725 1548);
FORCEPROP 2 LASTPROP $XRERR UNIQUE?
J 0
(-2320 1550);
DISPLAY 0.638298 (-2320 1550);
PAINT MONO (-2320 1550);
DISPLAY INVISIBLE (-2320 1550);
WIRE 16 -1 (-2950 1600)(-2350 1600);
FORCEPROP 2 LAST SIG_NAME TP_CPU1_RSVD_13
J 0
(-2725 1598);
DISPLAY 0.617021 (-2725 1598);
PAINT ORANGE (-2725 1598);
FORCEPROP 2 LASTPROP $XRERR UNIQUE?
J 0
(-2320 1600);
DISPLAY 0.638298 (-2320 1600);
PAINT MONO (-2320 1600);
DISPLAY INVISIBLE (-2320 1600);
WIRE 16 -1 (-2950 1650)(-2350 1650);
FORCEPROP 2 LAST SIG_NAME TP_CPU1_RSVD_14
J 0
(-2725 1648);
DISPLAY 0.617021 (-2725 1648);
PAINT ORANGE (-2725 1648);
FORCEPROP 2 LASTPROP $XRERR UNIQUE?
J 0
(-2320 1650);
DISPLAY 0.638298 (-2320 1650);
PAINT MONO (-2320 1650);
DISPLAY INVISIBLE (-2320 1650);
WIRE 16 -1 (-2950 1700)(-2350 1700);
FORCEPROP 2 LAST SIG_NAME TP_CPU1_RSVD_15
J 0
(-2725 1698);
DISPLAY 0.617021 (-2725 1698);
PAINT ORANGE (-2725 1698);
FORCEPROP 2 LASTPROP $XRERR UNIQUE?
J 0
(-2320 1700);
DISPLAY 0.638298 (-2320 1700);
PAINT MONO (-2320 1700);
DISPLAY INVISIBLE (-2320 1700);
WIRE 16 -1 (-2950 1750)(-2350 1750);
FORCEPROP 2 LAST SIG_NAME TP_CPU1_RSVD_16
J 0
(-2725 1748);
DISPLAY 0.617021 (-2725 1748);
PAINT ORANGE (-2725 1748);
FORCEPROP 2 LASTPROP $XRERR UNIQUE?
J 0
(-2320 1750);
DISPLAY 0.638298 (-2320 1750);
PAINT MONO (-2320 1750);
DISPLAY INVISIBLE (-2320 1750);
WIRE 16 -1 (-2950 1800)(-2350 1800);
FORCEPROP 2 LAST SIG_NAME TP_CPU1_RSVD_17
J 0
(-2725 1798);
DISPLAY 0.617021 (-2725 1798);
PAINT ORANGE (-2725 1798);
FORCEPROP 2 LASTPROP $XRERR UNIQUE?
J 0
(-2320 1800);
DISPLAY 0.638298 (-2320 1800);
PAINT MONO (-2320 1800);
DISPLAY INVISIBLE (-2320 1800);
WIRE 16 -1 (-2950 1850)(-2350 1850);
FORCEPROP 2 LAST SIG_NAME TP_CPU1_RSVD_18
J 0
(-2725 1848);
DISPLAY 0.617021 (-2725 1848);
PAINT ORANGE (-2725 1848);
FORCEPROP 2 LASTPROP $XRERR UNIQUE?
J 0
(-2320 1850);
DISPLAY 0.638298 (-2320 1850);
PAINT MONO (-2320 1850);
DISPLAY INVISIBLE (-2320 1850);
WIRE 16 -1 (-2950 1900)(-2350 1900);
FORCEPROP 2 LAST SIG_NAME TP_CPU1_RSVD_19
J 0
(-2725 1898);
DISPLAY 0.617021 (-2725 1898);
PAINT ORANGE (-2725 1898);
FORCEPROP 2 LASTPROP $XRERR UNIQUE?
J 0
(-2320 1900);
DISPLAY 0.638298 (-2320 1900);
PAINT MONO (-2320 1900);
DISPLAY INVISIBLE (-2320 1900);
WIRE 16 -1 (-2950 1950)(-2350 1950);
FORCEPROP 2 LAST SIG_NAME TP_CPU1_RSVD_20
J 0
(-2725 1948);
DISPLAY 0.617021 (-2725 1948);
PAINT ORANGE (-2725 1948);
FORCEPROP 2 LASTPROP $XRERR UNIQUE?
J 0
(-2320 1950);
DISPLAY 0.638298 (-2320 1950);
PAINT MONO (-2320 1950);
DISPLAY INVISIBLE (-2320 1950);
WIRE 16 -1 (-2950 2000)(-2350 2000);
FORCEPROP 2 LAST SIG_NAME TP_CPU1_RSVD_21
J 0
(-2725 1998);
DISPLAY 0.617021 (-2725 1998);
PAINT ORANGE (-2725 1998);
FORCEPROP 2 LASTPROP $XRERR UNIQUE?
J 0
(-2320 2000);
DISPLAY 0.638298 (-2320 2000);
PAINT MONO (-2320 2000);
DISPLAY INVISIBLE (-2320 2000);
WIRE 16 -1 (-2950 2050)(-2350 2050);
FORCEPROP 2 LAST SIG_NAME TP_CPU1_RSVD_22
J 0
(-2725 2048);
DISPLAY 0.617021 (-2725 2048);
PAINT ORANGE (-2725 2048);
FORCEPROP 2 LASTPROP $XRERR UNIQUE?
J 0
(-2320 2050);
DISPLAY 0.638298 (-2320 2050);
PAINT MONO (-2320 2050);
DISPLAY INVISIBLE (-2320 2050);
WIRE 16 -1 (-2950 2100)(-2350 2100);
FORCEPROP 2 LAST SIG_NAME TP_CPU1_RSVD_23
J 0
(-2725 2098);
DISPLAY 0.617021 (-2725 2098);
PAINT ORANGE (-2725 2098);
FORCEPROP 2 LASTPROP $XRERR UNIQUE?
J 0
(-2320 2100);
DISPLAY 0.638298 (-2320 2100);
PAINT MONO (-2320 2100);
DISPLAY INVISIBLE (-2320 2100);
WIRE 16 -1 (-2950 2150)(-2350 2150);
FORCEPROP 2 LAST SIG_NAME TP_CPU1_RSVD_24
J 0
(-2725 2148);
DISPLAY 0.617021 (-2725 2148);
PAINT ORANGE (-2725 2148);
FORCEPROP 2 LASTPROP $XRERR UNIQUE?
J 0
(-2320 2150);
DISPLAY 0.638298 (-2320 2150);
PAINT MONO (-2320 2150);
DISPLAY INVISIBLE (-2320 2150);
WIRE 16 -1 (-2950 2200)(-2350 2200);
FORCEPROP 2 LAST SIG_NAME TP_CPU1_RSVD_25
J 0
(-2725 2198);
DISPLAY 0.617021 (-2725 2198);
PAINT ORANGE (-2725 2198);
FORCEPROP 2 LASTPROP $XRERR UNIQUE?
J 0
(-2320 2200);
DISPLAY 0.638298 (-2320 2200);
PAINT MONO (-2320 2200);
DISPLAY INVISIBLE (-2320 2200);
WIRE 16 -1 (-2950 2250)(-2350 2250);
FORCEPROP 2 LAST SIG_NAME TP_CPU1_RSVD_26
J 0
(-2725 2248);
DISPLAY 0.617021 (-2725 2248);
PAINT ORANGE (-2725 2248);
FORCEPROP 2 LASTPROP $XRERR UNIQUE?
J 0
(-2320 2250);
DISPLAY 0.638298 (-2320 2250);
PAINT MONO (-2320 2250);
DISPLAY INVISIBLE (-2320 2250);
WIRE 16 -1 (-2950 2300)(-2350 2300);
FORCEPROP 2 LAST SIG_NAME TP_CPU1_RSVD_27
J 0
(-2725 2298);
DISPLAY 0.617021 (-2725 2298);
PAINT ORANGE (-2725 2298);
FORCEPROP 2 LASTPROP $XRERR UNIQUE?
J 0
(-2320 2300);
DISPLAY 0.638298 (-2320 2300);
PAINT MONO (-2320 2300);
DISPLAY INVISIBLE (-2320 2300);
WIRE 16 -1 (-2950 2350)(-2350 2350);
FORCEPROP 2 LAST SIG_NAME TP_CPU1_RSVD_28
J 0
(-2725 2348);
DISPLAY 0.617021 (-2725 2348);
PAINT ORANGE (-2725 2348);
FORCEPROP 2 LASTPROP $XRERR UNIQUE?
J 0
(-2320 2350);
DISPLAY 0.638298 (-2320 2350);
PAINT MONO (-2320 2350);
DISPLAY INVISIBLE (-2320 2350);
WIRE 16 -1 (-2950 2400)(-2350 2400);
FORCEPROP 2 LAST SIG_NAME TP_CPU1_RSVD_29
J 0
(-2725 2398);
DISPLAY 0.617021 (-2725 2398);
PAINT ORANGE (-2725 2398);
FORCEPROP 2 LASTPROP $XRERR UNIQUE?
J 0
(-2320 2400);
DISPLAY 0.638298 (-2320 2400);
PAINT MONO (-2320 2400);
DISPLAY INVISIBLE (-2320 2400);
WIRE 16 -1 (-2950 2450)(-2350 2450);
FORCEPROP 2 LAST SIG_NAME TP_CPU1_RSVD_30
J 0
(-2725 2448);
DISPLAY 0.617021 (-2725 2448);
PAINT ORANGE (-2725 2448);
FORCEPROP 2 LASTPROP $XRERR UNIQUE?
J 0
(-2320 2450);
DISPLAY 0.638298 (-2320 2450);
PAINT MONO (-2320 2450);
DISPLAY INVISIBLE (-2320 2450);
WIRE 16 -1 (-2950 2500)(-2350 2500);
FORCEPROP 2 LAST SIG_NAME TP_CPU1_RSVD_31
J 0
(-2725 2498);
DISPLAY 0.617021 (-2725 2498);
PAINT ORANGE (-2725 2498);
FORCEPROP 2 LASTPROP $XRERR UNIQUE?
J 0
(-2320 2500);
DISPLAY 0.638298 (-2320 2500);
PAINT MONO (-2320 2500);
DISPLAY INVISIBLE (-2320 2500);
WIRE 16 -1 (-2950 2550)(-2350 2550);
FORCEPROP 2 LAST SIG_NAME TP_CPU1_RSVD_32
J 0
(-2725 2548);
DISPLAY 0.617021 (-2725 2548);
PAINT ORANGE (-2725 2548);
FORCEPROP 2 LASTPROP $XRERR UNIQUE?
J 0
(-2320 2550);
DISPLAY 0.638298 (-2320 2550);
PAINT MONO (-2320 2550);
DISPLAY INVISIBLE (-2320 2550);
WIRE 16 -1 (-2950 2600)(-2350 2600);
FORCEPROP 2 LAST SIG_NAME TP_CPU1_RSVD_33
J 0
(-2725 2598);
DISPLAY 0.617021 (-2725 2598);
PAINT ORANGE (-2725 2598);
FORCEPROP 2 LASTPROP $XRERR UNIQUE?
J 0
(-2320 2600);
DISPLAY 0.638298 (-2320 2600);
PAINT MONO (-2320 2600);
DISPLAY INVISIBLE (-2320 2600);
WIRE 16 -1 (-2950 2650)(-2350 2650);
FORCEPROP 2 LAST SIG_NAME TP_CPU1_RSVD_34
J 0
(-2725 2648);
DISPLAY 0.617021 (-2725 2648);
PAINT ORANGE (-2725 2648);
FORCEPROP 2 LASTPROP $XRERR UNIQUE?
J 0
(-2320 2650);
DISPLAY 0.638298 (-2320 2650);
PAINT MONO (-2320 2650);
DISPLAY INVISIBLE (-2320 2650);
WIRE 16 -1 (-2950 2700)(-2350 2700);
FORCEPROP 2 LAST SIG_NAME TP_CPU1_RSVD_35
J 0
(-2725 2698);
DISPLAY 0.617021 (-2725 2698);
PAINT ORANGE (-2725 2698);
FORCEPROP 2 LASTPROP $XRERR UNIQUE?
J 0
(-2320 2700);
DISPLAY 0.638298 (-2320 2700);
PAINT MONO (-2320 2700);
DISPLAY INVISIBLE (-2320 2700);
WIRE 16 -1 (-2950 2750)(-2350 2750);
FORCEPROP 2 LAST SIG_NAME TP_CPU1_RSVD_36
J 0
(-2725 2748);
DISPLAY 0.617021 (-2725 2748);
PAINT ORANGE (-2725 2748);
FORCEPROP 2 LASTPROP $XRERR UNIQUE?
J 0
(-2320 2750);
DISPLAY 0.638298 (-2320 2750);
PAINT MONO (-2320 2750);
DISPLAY INVISIBLE (-2320 2750);
WIRE 16 -1 (-2950 2800)(-2350 2800);
FORCEPROP 2 LAST SIG_NAME TP_CPU1_RSVD_37
J 0
(-2725 2798);
DISPLAY 0.617021 (-2725 2798);
PAINT ORANGE (-2725 2798);
FORCEPROP 2 LASTPROP $XRERR UNIQUE?
J 0
(-2320 2800);
DISPLAY 0.638298 (-2320 2800);
PAINT MONO (-2320 2800);
DISPLAY INVISIBLE (-2320 2800);
WIRE 16 -1 (-2950 2850)(-2350 2850);
FORCEPROP 2 LAST SIG_NAME TP_CPU1_RSVD_38
J 0
(-2725 2848);
DISPLAY 0.617021 (-2725 2848);
PAINT ORANGE (-2725 2848);
FORCEPROP 2 LASTPROP $XRERR UNIQUE?
J 0
(-2320 2850);
DISPLAY 0.638298 (-2320 2850);
PAINT MONO (-2320 2850);
DISPLAY INVISIBLE (-2320 2850);
WIRE 16 -1 (-2950 2900)(-2350 2900);
FORCEPROP 2 LAST SIG_NAME TP_CPU1_RSVD_39
J 0
(-2725 2898);
DISPLAY 0.617021 (-2725 2898);
PAINT ORANGE (-2725 2898);
FORCEPROP 2 LASTPROP $XRERR UNIQUE?
J 0
(-2320 2900);
DISPLAY 0.638298 (-2320 2900);
PAINT MONO (-2320 2900);
DISPLAY INVISIBLE (-2320 2900);
WIRE 16 -1 (-2950 2950)(-2350 2950);
FORCEPROP 2 LAST SIG_NAME TP_CPU1_RSVD_40
J 0
(-2725 2948);
DISPLAY 0.617021 (-2725 2948);
PAINT ORANGE (-2725 2948);
FORCEPROP 2 LASTPROP $XRERR UNIQUE?
J 0
(-2320 2950);
DISPLAY 0.638298 (-2320 2950);
PAINT MONO (-2320 2950);
DISPLAY INVISIBLE (-2320 2950);
WIRE 16 -1 (-2950 3000)(-2350 3000);
FORCEPROP 2 LAST SIG_NAME TP_CPU1_RSVD_41
J 0
(-2725 2998);
DISPLAY 0.617021 (-2725 2998);
PAINT ORANGE (-2725 2998);
FORCEPROP 2 LASTPROP $XRERR UNIQUE?
J 0
(-2320 3000);
DISPLAY 0.638298 (-2320 3000);
PAINT MONO (-2320 3000);
DISPLAY INVISIBLE (-2320 3000);
WIRE 16 -1 (-2950 3050)(-2350 3050);
FORCEPROP 2 LAST SIG_NAME TP_CPU1_RSVD_42
J 0
(-2725 3048);
DISPLAY 0.617021 (-2725 3048);
PAINT ORANGE (-2725 3048);
FORCEPROP 2 LASTPROP $XRERR UNIQUE?
J 0
(-2320 3050);
DISPLAY 0.638298 (-2320 3050);
PAINT MONO (-2320 3050);
DISPLAY INVISIBLE (-2320 3050);
WIRE 16 -1 (-2950 3100)(-2350 3100);
FORCEPROP 2 LAST SIG_NAME TP_CPU1_RSVD_43
J 0
(-2725 3098);
DISPLAY 0.617021 (-2725 3098);
PAINT ORANGE (-2725 3098);
FORCEPROP 2 LASTPROP $XRERR UNIQUE?
J 0
(-2320 3100);
DISPLAY 0.638298 (-2320 3100);
PAINT MONO (-2320 3100);
DISPLAY INVISIBLE (-2320 3100);
WIRE 16 -1 (-2950 3150)(-2350 3150);
FORCEPROP 2 LAST SIG_NAME TP_CPU1_RSVD_44
J 0
(-2725 3148);
DISPLAY 0.617021 (-2725 3148);
PAINT ORANGE (-2725 3148);
FORCEPROP 2 LASTPROP $XRERR UNIQUE?
J 0
(-2320 3150);
DISPLAY 0.638298 (-2320 3150);
PAINT MONO (-2320 3150);
DISPLAY INVISIBLE (-2320 3150);
WIRE 16 -1 (-2950 3200)(-2350 3200);
FORCEPROP 2 LAST SIG_NAME TP_CPU1_RSVD_45
J 0
(-2725 3198);
DISPLAY 0.617021 (-2725 3198);
PAINT ORANGE (-2725 3198);
FORCEPROP 2 LASTPROP $XRERR UNIQUE?
J 0
(-2320 3200);
DISPLAY 0.638298 (-2320 3200);
PAINT MONO (-2320 3200);
DISPLAY INVISIBLE (-2320 3200);
WIRE 16 -1 (-2950 3250)(-2350 3250);
FORCEPROP 2 LAST SIG_NAME TP_CPU1_RSVD_46
J 0
(-2725 3248);
DISPLAY 0.617021 (-2725 3248);
PAINT ORANGE (-2725 3248);
FORCEPROP 2 LASTPROP $XRERR UNIQUE?
J 0
(-2320 3250);
DISPLAY 0.638298 (-2320 3250);
PAINT MONO (-2320 3250);
DISPLAY INVISIBLE (-2320 3250);
WIRE 16 -1 (-2950 3300)(-2350 3300);
FORCEPROP 2 LAST SIG_NAME TP_CPU1_RSVD_47
J 0
(-2725 3298);
DISPLAY 0.617021 (-2725 3298);
PAINT ORANGE (-2725 3298);
FORCEPROP 2 LASTPROP $XRERR UNIQUE?
J 0
(-2320 3300);
DISPLAY 0.638298 (-2320 3300);
PAINT MONO (-2320 3300);
DISPLAY INVISIBLE (-2320 3300);
WIRE 16 -1 (-2950 3350)(-2350 3350);
FORCEPROP 2 LAST SIG_NAME TP_CPU1_RSVD_48
J 0
(-2725 3348);
DISPLAY 0.617021 (-2725 3348);
PAINT ORANGE (-2725 3348);
FORCEPROP 2 LASTPROP $XRERR UNIQUE?
J 0
(-2320 3350);
DISPLAY 0.638298 (-2320 3350);
PAINT MONO (-2320 3350);
DISPLAY INVISIBLE (-2320 3350);
WIRE 16 -1 (-2950 3400)(-2350 3400);
FORCEPROP 2 LAST SIG_NAME TP_CPU1_RSVD_49
J 0
(-2725 3398);
DISPLAY 0.617021 (-2725 3398);
PAINT ORANGE (-2725 3398);
FORCEPROP 2 LASTPROP $XRERR UNIQUE?
J 0
(-2320 3400);
DISPLAY 0.638298 (-2320 3400);
PAINT MONO (-2320 3400);
DISPLAY INVISIBLE (-2320 3400);
WIRE 16 -1 (-2950 3450)(-2350 3450);
FORCEPROP 2 LAST SIG_NAME TP_CPU1_RSVD_50
J 0
(-2725 3448);
DISPLAY 0.617021 (-2725 3448);
PAINT ORANGE (-2725 3448);
FORCEPROP 2 LASTPROP $XRERR UNIQUE?
J 0
(-2320 3450);
DISPLAY 0.638298 (-2320 3450);
PAINT MONO (-2320 3450);
DISPLAY INVISIBLE (-2320 3450);
WIRE 16 -1 (-2950 3500)(-2350 3500);
FORCEPROP 2 LAST SIG_NAME TP_CPU1_RSVD_51
J 0
(-2725 3498);
DISPLAY 0.617021 (-2725 3498);
PAINT ORANGE (-2725 3498);
FORCEPROP 2 LASTPROP $XRERR UNIQUE?
J 0
(-2320 3500);
DISPLAY 0.638298 (-2320 3500);
PAINT MONO (-2320 3500);
DISPLAY INVISIBLE (-2320 3500);
WIRE 16 -1 (-2950 3600)(-2350 3600);
FORCEPROP 2 LAST SIG_NAME TP_CPU1_RSVD_53
J 0
(-2725 3598);
DISPLAY 0.617021 (-2725 3598);
PAINT ORANGE (-2725 3598);
FORCEPROP 2 LASTPROP $XRERR UNIQUE?
J 0
(-2320 3600);
DISPLAY 0.638298 (-2320 3600);
PAINT MONO (-2320 3600);
DISPLAY INVISIBLE (-2320 3600);
WIRE 16 -1 (-2950 3650)(-2350 3650);
FORCEPROP 2 LAST SIG_NAME TP_CPU1_RSVD_54
J 0
(-2725 3648);
DISPLAY 0.617021 (-2725 3648);
PAINT ORANGE (-2725 3648);
FORCEPROP 2 LASTPROP $XRERR UNIQUE?
J 0
(-2320 3650);
DISPLAY 0.638298 (-2320 3650);
PAINT MONO (-2320 3650);
DISPLAY INVISIBLE (-2320 3650);
WIRE 16 -1 (-2950 3700)(-2350 3700);
FORCEPROP 2 LAST SIG_NAME TP_CPU1_RSVD_55
J 0
(-2725 3698);
DISPLAY 0.617021 (-2725 3698);
PAINT ORANGE (-2725 3698);
FORCEPROP 2 LASTPROP $XRERR UNIQUE?
J 0
(-2320 3700);
DISPLAY 0.638298 (-2320 3700);
PAINT MONO (-2320 3700);
DISPLAY INVISIBLE (-2320 3700);
WIRE 16 -1 (-2950 3750)(-2350 3750);
FORCEPROP 2 LAST SIG_NAME TP_CPU1_RSVD_56
J 0
(-2725 3748);
DISPLAY 0.617021 (-2725 3748);
PAINT ORANGE (-2725 3748);
FORCEPROP 2 LASTPROP $XRERR UNIQUE?
J 0
(-2320 3750);
DISPLAY 0.638298 (-2320 3750);
PAINT MONO (-2320 3750);
DISPLAY INVISIBLE (-2320 3750);
WIRE 16 -1 (-2950 3800)(-2350 3800);
FORCEPROP 2 LAST SIG_NAME TP_CPU1_RSVD_57
J 0
(-2725 3798);
DISPLAY 0.617021 (-2725 3798);
PAINT ORANGE (-2725 3798);
FORCEPROP 2 LASTPROP $XRERR UNIQUE?
J 0
(-2320 3800);
DISPLAY 0.638298 (-2320 3800);
PAINT MONO (-2320 3800);
DISPLAY INVISIBLE (-2320 3800);
WIRE 16 -1 (-2950 3900)(-2350 3900);
FORCEPROP 2 LAST SIG_NAME TP_CPU1_RSVD_59
J 0
(-2725 3898);
DISPLAY 0.617021 (-2725 3898);
PAINT ORANGE (-2725 3898);
FORCEPROP 2 LASTPROP $XRERR UNIQUE?
J 0
(-2320 3900);
DISPLAY 0.638298 (-2320 3900);
PAINT MONO (-2320 3900);
DISPLAY INVISIBLE (-2320 3900);
WIRE 16 -1 (-2950 3950)(-2350 3950);
FORCEPROP 2 LAST SIG_NAME TP_CPU1_RSVD_60
J 0
(-2725 3948);
DISPLAY 0.617021 (-2725 3948);
PAINT ORANGE (-2725 3948);
FORCEPROP 2 LASTPROP $XRERR UNIQUE?
J 0
(-2320 3950);
DISPLAY 0.638298 (-2320 3950);
PAINT MONO (-2320 3950);
DISPLAY INVISIBLE (-2320 3950);
DOT 1 (-5350 3750);
DOT 1 (-5350 3800);
DOT 1 (-5250 2800);
DOT 1 (-5225 1700);
DOT 1 (-5250 2700);
DOT 1 (-5250 2750);
DOT 1 (-5350 3050);
DOT 1 (-5225 1850);
DOT 1 (-1800 3850);
DOT 1 (-5350 3600);
DOT 1 (-5225 1400);
DOT 1 (-5350 3500);
DOT 1 (-5350 3100);
DOT 1 (-5350 3000);
DOT 1 (-5350 2950);
DOT 1 (-5350 3300);
DOT 1 (-5350 3350);
DOT 1 (-5350 3450);
DOT 1 (-5350 3550);
DOT 1 (-5350 3650);
DOT 1 (-5350 3700);
DOT 1 (-5350 3900);
DOT 1 (-5350 3950);
DOT 1 (-5350 3150);
DOT 1 (-5350 3200);
DOT 1 (-5350 3250);
DOT 1 (-5225 1550);
FORCENOTE
BOM_COST=PROC_SOCKET
(-7925 200) 0;
DISPLAY LEFT (-7925 200);
DISPLAY 1.723404 (-7925 200);
PAINT PURPLE (-7925 200);
FORCENOTE
ROOM=CPU1
(-7925 325) 0;
DISPLAY LEFT (-7925 325);
DISPLAY 1.723404 (-7925 325);
PAINT PURPLE (-7925 325);
QUIT
